(kicad_pcb
	(version 20260206)
	(generator "pcbnew")
	(generator_version "10.0")
	(general
		(thickness 1.6)
		(legacy_teardrops no)
	)
	(paper "A4")
	(title_block
		(title "panther-plus-userver — 13130-1b_20150205.brd")
		(comment 1 "Honey Badger (Wiwynn) / footprints 365-372 of 1509")
	)
	(layers
		(0 "F.Cu" signal "TOP")
		(4 "In1.Cu" signal "L2")
		(6 "In2.Cu" signal "L3")
		(8 "In3.Cu" signal "L4")
		(10 "In4.Cu" signal "L5")
		(12 "In5.Cu" signal "L6")
		(14 "In6.Cu" signal "L7")
		(16 "In7.Cu" signal "L8")
		(18 "In8.Cu" signal "L9")
		(20 "In9.Cu" signal "L10")
		(22 "In10.Cu" signal "L11")
		(2 "B.Cu" signal "BOTTOM")
		(9 "F.Adhes" user "F.Adhesive")
		(11 "B.Adhes" user "B.Adhesive")
		(13 "F.Paste" user "Package Geometry/Pastemask Top")
		(15 "B.Paste" user "Package Geometry/Pastemask Bottom")
		(5 "F.SilkS" user "Ref Des/Silkscreen Top")
		(7 "B.SilkS" user "Ref Des/Silkscreen Bottom")
		(1 "F.Mask" user "Board Geometry/Soldermask Top")
		(3 "B.Mask" user "Board Geometry/Soldermask Bottom")
		(17 "Dwgs.User" user "User.Drawings")
		(19 "Cmts.User" user "User.Comments")
		(21 "Eco1.User" user "User.Eco1")
		(23 "Eco2.User" user "User.Eco2")
		(25 "Edge.Cuts" user "Board Geometry/Outline")
		(27 "Margin" user)
		(31 "F.CrtYd" user "Package Geometry/Place Bound Top")
		(29 "B.CrtYd" user "Package Geometry/Place Bound Bottom")
		(35 "F.Fab" user "Ref Des/Assembly Top")
		(33 "B.Fab" user "Ref Des/Assembly Bottom")
	)
	(footprint ""
		(layer "F.Cu")
		(at 154.813 -50.927 180)
		(property "Reference" "TP39"
			(at 0 0 180)
			(layer "F.SilkS")
			(hide yes)
			(effects
				(font
					(size 1.27 1.27)
				)
			)
		)
		(property "Value" "TPAD32-GP"
			(at 0 -3.166364 180)
			(unlocked yes)
			(layer "F.Fab")
			(hide yes)
			(effects
				(font
					(size 1.016 1.016)
					(thickness 0.1524)
				)
			)
		)
		(property "Device Type" "TPAD32"
			(at 0 -4.690618 180)
			(unlocked yes)
			(layer "F.Fab")
			(hide yes)
			(effects
				(font
					(size 1.016 1.016)
					(thickness 0.1524)
				)
			)
		)
		(duplicate_pad_numbers_are_jumpers no)
		(fp_poly
			(pts
				(arc
					(start -0.7112 0)
					(mid 0.7112 0)
					(end -0.7112 0)
				)
			)
			(stroke
				(width 0)
				(type default)
			)
			(fill no)
			(layer "F.CrtYd")
		)
		(fp_poly
			(pts
				(arc
					(start -0.7112 0)
					(mid 0.7112 0)
					(end -0.7112 0)
				)
			)
			(stroke
				(width 0)
				(type default)
			)
			(fill no)
			(layer "F.Fab")
		)
		(pad "1" smd circle
			(at 0 0 180)
			(size 0.8128 0.8128)
			(layers "F.Cu" "F.Mask" "F.Paste")
			(net "C_ASDO")
		)
	)
	(footprint ""
		(layer "F.Cu")
		(at 70.612 -50.038 -90)
		(property "Reference" "Q5"
			(at 0 0 270)
			(layer "F.SilkS")
			(hide yes)
			(effects
				(font
					(size 1.27 1.27)
				)
			)
		)
		(property "Value" "2N7002A-7-GP"
			(at -4.3561 -5.7912 270)
			(unlocked yes)
			(layer "F.Fab")
			(hide yes)
			(effects
				(font
					(size 1.016 1.016)
					(thickness 0.1524)
				)
			)
		)
		(property "Device Type" "SOT23DGS2D4H48"
			(at -4.3561 -7.3152 270)
			(unlocked yes)
			(layer "F.Fab")
			(hide yes)
			(effects
				(font
					(size 1.016 1.016)
					(thickness 0.1524)
				)
			)
		)
		(duplicate_pad_numbers_are_jumpers no)
		(fp_line
			(start -1.7145 0.4445)
			(end 1.7145 0.4445)
			(stroke
				(width 0.1524)
				(type default)
			)
			(layer "F.SilkS")
		)
		(fp_line
			(start 1.7145 0.4445)
			(end 1.7145 -0.4445)
			(stroke
				(width 0.1524)
				(type default)
			)
			(layer "F.SilkS")
		)
		(fp_line
			(start -1.7145 -0.4445)
			(end -1.7145 0.4445)
			(stroke
				(width 0.1524)
				(type default)
			)
			(layer "F.SilkS")
		)
		(fp_line
			(start 1.7145 -0.4445)
			(end -1.7145 -0.4445)
			(stroke
				(width 0.1524)
				(type default)
			)
			(layer "F.SilkS")
		)
		(fp_poly
			(pts
				(xy -1.4224 1.5621) (xy -1.4224 0.9017) (xy -1.7145 0.9017) (xy -1.7145 -0.9017) (xy -0.4699 -0.9017)
				(xy -0.4699 -1.5621) (xy 0.4699 -1.5621) (xy 0.4699 -0.9017) (xy 1.7145 -0.9017) (xy 1.7145 0.9017)
				(xy 1.4224 0.9017) (xy 1.4224 1.5621) (xy 0.4826 1.5621) (xy 0.4826 0.9017) (xy -0.4826 0.9017)
				(xy -0.4826 1.5621)
			)
			(stroke
				(width 0)
				(type default)
			)
			(fill no)
			(layer "F.CrtYd")
		)
		(fp_poly
			(pts
				(xy -1.4224 1.5621) (xy -1.4224 0.9017) (xy -1.7145 0.9017) (xy -1.7145 -0.9017) (xy -0.4699 -0.9017)
				(xy -0.4699 -1.5621) (xy 0.4699 -1.5621) (xy 0.4699 -0.9017) (xy 1.7145 -0.9017) (xy 1.7145 0.9017)
				(xy 1.4224 0.9017) (xy 1.4224 1.5621) (xy 0.4826 1.5621) (xy 0.4826 0.9017) (xy -0.4826 0.9017)
				(xy -0.4826 1.5621)
			)
			(stroke
				(width 0)
				(type default)
			)
			(fill no)
			(layer "F.Fab")
		)
		(pad "D" smd custom
			(at 0 -1.069086 270)
			(size 0.17145 0.17145)
			(layers "F.Cu" "F.Mask" "F.Paste")
			(net "BEEP_LED_D")
			(options
				(clearance outline)
				(anchor circle)
			)
			(primitives
				(gr_poly
					(pts
						(arc
							(start -0.1397 0.3683)
							(mid -0.283384 0.308784)
							(end -0.3429 0.1651)
						)
						(arc
							(start -0.3429 -0.1651)
							(mid -0.283384 -0.308784)
							(end -0.1397 -0.3683)
						)
						(arc
							(start 0.1397 -0.3683)
							(mid 0.283384 -0.308784)
							(end 0.3429 -0.1651)
						)
						(arc
							(start 0.3429 0.1651)
							(mid 0.283384 0.308784)
							(end 0.1397 0.3683)
						)
					)
					(width 0)
					(fill yes)
				)
			)
		)
		(pad "G" smd custom
			(at -0.94996 1.069086 270)
			(size 0.17145 0.17145)
			(layers "F.Cu" "F.Mask" "F.Paste")
			(net "CPU_BEEP_LED")
			(options
				(clearance outline)
				(anchor circle)
			)
			(primitives
				(gr_poly
					(pts
						(arc
							(start -0.1397 0.3683)
							(mid -0.283384 0.308784)
							(end -0.3429 0.1651)
						)
						(arc
							(start -0.3429 -0.1651)
							(mid -0.283384 -0.308784)
							(end -0.1397 -0.3683)
						)
						(arc
							(start 0.1397 -0.3683)
							(mid 0.283384 -0.308784)
							(end 0.3429 -0.1651)
						)
						(arc
							(start 0.3429 0.1651)
							(mid 0.283384 0.308784)
							(end 0.1397 0.3683)
						)
					)
					(width 0)
					(fill yes)
				)
			)
		)
		(pad "S" smd custom
			(at 0.94996 1.069086 270)
			(size 0.17145 0.17145)
			(layers "F.Cu" "F.Mask" "F.Paste")
			(net "GND")
			(options
				(clearance outline)
				(anchor circle)
			)
			(primitives
				(gr_poly
					(pts
						(arc
							(start -0.1397 0.3683)
							(mid -0.283384 0.308784)
							(end -0.3429 0.1651)
						)
						(arc
							(start -0.3429 -0.1651)
							(mid -0.283384 -0.308784)
							(end -0.1397 -0.3683)
						)
						(arc
							(start 0.1397 -0.3683)
							(mid 0.283384 -0.308784)
							(end 0.3429 -0.1651)
						)
						(arc
							(start 0.3429 0.1651)
							(mid 0.283384 0.308784)
							(end 0.1397 0.3683)
						)
					)
					(width 0)
					(fill yes)
				)
			)
		)
	)
	(footprint ""
		(layer "F.Cu")
		(at 187.198 -39.878 180)
		(property "Reference" "PC86"
			(at 0 0 180)
			(layer "F.SilkS")
			(hide yes)
			(effects
				(font
					(size 1.27 1.27)
				)
			)
		)
		(property "Value" "SC1KP50V2KX-1GP"
			(at 1.8923 -1.2065 180)
			(unlocked yes)
			(layer "F.Fab")
			(hide yes)
			(effects
				(font
					(size 1.016 1.016)
					(thickness 0.1524)
				)
			)
		)
		(property "Device Type" "C402H22"
			(at 1.8923 -2.7305 180)
			(unlocked yes)
			(layer "F.Fab")
			(hide yes)
			(effects
				(font
					(size 1.016 1.016)
					(thickness 0.1524)
				)
			)
		)
		(duplicate_pad_numbers_are_jumpers no)
		(fp_rect
			(start -0.381 0.7366)
			(end 0.381 -0.7366)
			(stroke
				(width 0)
				(type default)
			)
			(fill no)
			(layer "F.CrtYd")
		)
		(fp_rect
			(start -0.381 0.7366)
			(end 0.381 -0.7366)
			(stroke
				(width 0)
				(type default)
			)
			(fill no)
			(layer "F.Fab")
		)
		(pad "1" smd custom
			(at 0 -0.4572 180)
			(size 0.1143 0.1143)
			(layers "F.Cu" "F.Mask" "F.Paste")
			(net "VR_PVDDR_A_IAUTO")
			(options
				(clearance outline)
				(anchor circle)
			)
			(primitives
				(gr_poly
					(pts
						(arc
							(start -0.254 -0.1778)
							(mid -0.239121 -0.213721)
							(end -0.2032 -0.2286)
						)
						(arc
							(start 0.2032 -0.2286)
							(mid 0.239121 -0.213721)
							(end 0.254 -0.1778)
						)
						(arc
							(start 0.254 0.1778)
							(mid 0.239121 0.213721)
							(end 0.2032 0.2286)
						)
						(arc
							(start -0.2032 0.2286)
							(mid -0.239121 0.213721)
							(end -0.254 0.1778)
						)
					)
					(width 0)
					(fill yes)
				)
			)
		)
		(pad "2" smd custom
			(at 0 0.4572 180)
			(size 0.1143 0.1143)
			(layers "F.Cu" "F.Mask" "F.Paste")
			(net "GND")
			(options
				(clearance outline)
				(anchor circle)
			)
			(primitives
				(gr_poly
					(pts
						(arc
							(start -0.254 -0.1778)
							(mid -0.239121 -0.213721)
							(end -0.2032 -0.2286)
						)
						(arc
							(start 0.2032 -0.2286)
							(mid 0.239121 -0.213721)
							(end 0.254 -0.1778)
						)
						(arc
							(start 0.254 0.1778)
							(mid 0.239121 0.213721)
							(end 0.2032 0.2286)
						)
						(arc
							(start -0.2032 0.2286)
							(mid -0.239121 0.213721)
							(end -0.254 0.1778)
						)
					)
					(width 0)
					(fill yes)
				)
			)
		)
	)
	(footprint ""
		(layer "F.Cu")
		(at 12.1285 -64.897 -90)
		(property "Reference" "C158"
			(at 0 0 270)
			(layer "F.SilkS")
			(hide yes)
			(effects
				(font
					(size 1.27 1.27)
				)
			)
		)
		(property "Value" "SC10U6D3V5KX-4GP"
			(at 0 -4.9022 270)
			(unlocked yes)
			(layer "F.Fab")
			(hide yes)
			(effects
				(font
					(size 1.016 1.016)
					(thickness 0.1524)
				)
			)
		)
		(property "Device Type" "C805H58"
			(at 0 -6.8072 270)
			(unlocked yes)
			(layer "F.Fab")
			(hide yes)
			(effects
				(font
					(size 1.016 1.016)
					(thickness 0.1524)
				)
			)
		)
		(duplicate_pad_numbers_are_jumpers no)
		(fp_line
			(start 0.6096 0)
			(end -0.6096 0)
			(stroke
				(width 0.3048)
				(type default)
			)
			(layer "F.SilkS")
		)
		(fp_poly
			(pts
				(xy -0.9017 1.4351) (xy 0.9017 1.4351) (xy 0.9017 -1.4351) (xy -0.9017 -1.4351)
			)
			(stroke
				(width 0)
				(type default)
			)
			(fill no)
			(layer "F.CrtYd")
		)
		(fp_poly
			(pts
				(xy 0.9017 1.4351) (xy 0.9017 -1.4351) (xy -0.9017 -1.4351) (xy -0.9017 1.4351)
			)
			(stroke
				(width 0)
				(type default)
			)
			(fill no)
			(layer "F.Fab")
		)
		(pad "1" smd rect
			(at 0 -0.8382 270)
			(size 1.5494 0.9398)
			(layers "F.Cu" "F.Mask" "F.Paste")
			(net "P3V3")
		)
		(pad "2" smd rect
			(at 0 0.8382 270)
			(size 1.5494 0.9398)
			(layers "F.Cu" "F.Mask" "F.Paste")
			(net "GND")
		)
	)
	(footprint ""
		(layer "F.Cu")
		(at 27.0764 -55.6514 90)
		(property "Reference" "PR58"
			(at 0 0 90)
			(layer "F.SilkS")
			(hide yes)
			(effects
				(font
					(size 1.27 1.27)
				)
			)
		)
		(property "Value" "0R3J-0-U-GP"
			(at -0.0254 -2.0193 90)
			(unlocked yes)
			(layer "F.Fab")
			(hide yes)
			(effects
				(font
					(size 1.016 1.016)
					(thickness 0.1524)
				)
			)
		)
		(property "Device Type" "R603H22"
			(at -0.0254 -3.5433 90)
			(unlocked yes)
			(layer "F.Fab")
			(hide yes)
			(effects
				(font
					(size 1.016 1.016)
					(thickness 0.1524)
				)
			)
		)
		(duplicate_pad_numbers_are_jumpers no)
		(fp_line
			(start 0.4318 0)
			(end 0.2032 0)
			(stroke
				(width 0.2032)
				(type default)
			)
			(layer "F.SilkS")
		)
		(fp_line
			(start -0.2032 0)
			(end -0.4191 0)
			(stroke
				(width 0.2032)
				(type default)
			)
			(layer "F.SilkS")
		)
		(fp_rect
			(start -0.635 1.1811)
			(end 0.635 -1.1811)
			(stroke
				(width 0)
				(type default)
			)
			(fill no)
			(layer "F.CrtYd")
		)
		(fp_rect
			(start -0.635 1.1811)
			(end 0.635 -1.1811)
			(stroke
				(width 0)
				(type default)
			)
			(fill no)
			(layer "F.Fab")
		)
		(pad "1" smd custom
			(at 0 -0.6604 90)
			(size 0.19685 0.19685)
			(layers "F.Cu" "F.Mask" "F.Paste")
			(net "VR_PVCCP_GH")
			(options
				(clearance outline)
				(anchor circle)
			)
			(primitives
				(gr_poly
					(pts
						(arc
							(start 0.508 -0.2921)
							(mid 0.478242 -0.363942)
							(end 0.4064 -0.3937)
						)
						(arc
							(start -0.4064 -0.3937)
							(mid -0.478242 -0.363942)
							(end -0.508 -0.2921)
						)
						(arc
							(start -0.508 0.2921)
							(mid -0.478242 0.363942)
							(end -0.4064 0.3937)
						)
						(arc
							(start 0.4064 0.3937)
							(mid 0.478242 0.363942)
							(end 0.508 0.2921)
						)
					)
					(width 0)
					(fill yes)
				)
			)
		)
		(pad "2" smd custom
			(at 0 0.6604 90)
			(size 0.19685 0.19685)
			(layers "F.Cu" "F.Mask" "F.Paste")
			(net "VR_PVCCP_GH_R")
			(options
				(clearance outline)
				(anchor circle)
			)
			(primitives
				(gr_poly
					(pts
						(arc
							(start 0.508 -0.2921)
							(mid 0.478242 -0.363942)
							(end 0.4064 -0.3937)
						)
						(arc
							(start -0.4064 -0.3937)
							(mid -0.478242 -0.363942)
							(end -0.508 -0.2921)
						)
						(arc
							(start -0.508 0.2921)
							(mid -0.478242 0.363942)
							(end -0.4064 0.3937)
						)
						(arc
							(start 0.4064 0.3937)
							(mid 0.478242 0.363942)
							(end 0.508 0.2921)
						)
					)
					(width 0)
					(fill yes)
				)
			)
		)
	)
	(footprint ""
		(layer "F.Cu")
		(at 59.309 -56.769)
		(property "Reference" "PC59"
			(at 0 0 0)
			(layer "F.SilkS")
			(hide yes)
			(effects
				(font
					(size 1.27 1.27)
				)
			)
		)
		(property "Value" "SC47U6D3V5MX-1-GP"
			(at -0.0762 -6.1214 0)
			(unlocked yes)
			(layer "F.Fab")
			(hide yes)
			(effects
				(font
					(size 1.016 1.016)
					(thickness 0.1524)
				)
			)
		)
		(property "Device Type" "C805H54"
			(at -0.0762 -8.1534 0)
			(unlocked yes)
			(layer "F.Fab")
			(hide yes)
			(effects
				(font
					(size 1.016 1.016)
					(thickness 0.1524)
				)
			)
		)
		(duplicate_pad_numbers_are_jumpers no)
		(fp_line
			(start 0.6096 0)
			(end -0.6096 0)
			(stroke
				(width 0.3048)
				(type default)
			)
			(layer "F.SilkS")
		)
		(fp_poly
			(pts
				(xy -0.9017 1.4351) (xy 0.9017 1.4351) (xy 0.9017 -1.4351) (xy -0.9017 -1.4351)
			)
			(stroke
				(width 0)
				(type default)
			)
			(fill no)
			(layer "F.CrtYd")
		)
		(fp_poly
			(pts
				(xy 0.9017 1.4351) (xy 0.9017 -1.4351) (xy -0.9017 -1.4351) (xy -0.9017 1.4351)
			)
			(stroke
				(width 0)
				(type default)
			)
			(fill no)
			(layer "F.Fab")
		)
		(pad "1" smd rect
			(at 0 -0.8382)
			(size 1.5494 0.9398)
			(layers "F.Cu" "F.Mask" "F.Paste")
			(net "PVCCP")
		)
		(pad "2" smd rect
			(at 0 0.8382)
			(size 1.5494 0.9398)
			(layers "F.Cu" "F.Mask" "F.Paste")
			(net "GND")
		)
	)
	(footprint ""
		(layer "F.Cu")
		(at 45.212 -15.494 -90)
		(property "Reference" "L11"
			(at 0 0 270)
			(layer "F.SilkS")
			(hide yes)
			(effects
				(font
					(size 1.27 1.27)
				)
			)
		)
		(property "Value" "BLM18PG330SN1D-GP"
			(at -0.0254 -2.0193 270)
			(unlocked yes)
			(layer "F.Fab")
			(hide yes)
			(effects
				(font
					(size 1.016 1.016)
					(thickness 0.1524)
				)
			)
		)
		(property "Device Type" "L1608-UH38"
			(at -0.0254 -3.5433 270)
			(unlocked yes)
			(layer "F.Fab")
			(hide yes)
			(effects
				(font
					(size 1.016 1.016)
					(thickness 0.1524)
				)
			)
		)
		(duplicate_pad_numbers_are_jumpers no)
		(fp_line
			(start -0.4064 0)
			(end 0.4064 0)
			(stroke
				(width 0.2032)
				(type default)
			)
			(layer "F.SilkS")
		)
		(fp_rect
			(start -0.635 1.1811)
			(end 0.635 -1.1811)
			(stroke
				(width 0)
				(type default)
			)
			(fill no)
			(layer "F.CrtYd")
		)
		(fp_rect
			(start -0.635 1.1811)
			(end 0.635 -1.1811)
			(stroke
				(width 0)
				(type default)
			)
			(fill no)
			(layer "F.Fab")
		)
		(pad "1" smd custom
			(at 0 -0.6604 270)
			(size 0.19685 0.19685)
			(layers "F.Cu" "F.Mask" "F.Paste")
			(net "P3V3")
			(options
				(clearance outline)
				(anchor circle)
			)
			(primitives
				(gr_poly
					(pts
						(arc
							(start 0.508 -0.2921)
							(mid 0.478242 -0.363942)
							(end 0.4064 -0.3937)
						)
						(arc
							(start -0.4064 -0.3937)
							(mid -0.478242 -0.363942)
							(end -0.508 -0.2921)
						)
						(arc
							(start -0.508 0.2921)
							(mid -0.478242 0.363942)
							(end -0.4064 0.3937)
						)
						(arc
							(start 0.4064 0.3937)
							(mid 0.478242 0.363942)
							(end 0.508 0.2921)
						)
					)
					(width 0)
					(fill yes)
				)
			)
		)
		(pad "2" smd custom
			(at 0 0.6604 270)
			(size 0.19685 0.19685)
			(layers "F.Cu" "F.Mask" "F.Paste")
			(net "P3V3_VDD_CLKBUFF_R")
			(options
				(clearance outline)
				(anchor circle)
			)
			(primitives
				(gr_poly
					(pts
						(arc
							(start 0.508 -0.2921)
							(mid 0.478242 -0.363942)
							(end 0.4064 -0.3937)
						)
						(arc
							(start -0.4064 -0.3937)
							(mid -0.478242 -0.363942)
							(end -0.508 -0.2921)
						)
						(arc
							(start -0.508 0.2921)
							(mid -0.478242 0.363942)
							(end -0.4064 0.3937)
						)
						(arc
							(start 0.4064 0.3937)
							(mid 0.478242 0.363942)
							(end 0.508 0.2921)
						)
					)
					(width 0)
					(fill yes)
				)
			)
		)
	)
	(footprint ""
		(layer "F.Cu")
		(at 156.464 -28.956 180)
		(property "Reference" "R141"
			(at 0 0 180)
			(layer "F.SilkS")
			(hide yes)
			(effects
				(font
					(size 1.27 1.27)
				)
			)
		)
		(property "Value" "4K7R2F-GP"
			(at 0.064008 -3.993896 180)
			(unlocked yes)
			(layer "F.Fab")
			(hide yes)
			(effects
				(font
					(size 1.016 1.016)
					(thickness 0.1524)
				)
			)
		)
		(property "Device Type" "R402H16"
			(at 0.064008 -5.517896 180)
			(unlocked yes)
			(layer "F.Fab")
			(hide yes)
			(effects
				(font
					(size 1.016 1.016)
					(thickness 0.1524)
				)
			)
		)
		(duplicate_pad_numbers_are_jumpers no)
		(fp_rect
			(start -0.381 0.8382)
			(end 0.381 -0.8382)
			(stroke
				(width 0)
				(type default)
			)
			(fill no)
			(layer "F.CrtYd")
		)
		(fp_rect
			(start -0.381 0.8382)
			(end 0.381 -0.8382)
			(stroke
				(width 0)
				(type default)
			)
			(fill no)
			(layer "F.Fab")
		)
		(pad "1" smd custom
			(at 0 -0.4318 180)
			(size 0.127 0.127)
			(layers "F.Cu" "F.Mask" "F.Paste")
			(net "P3V3_STBY")
			(options
				(clearance outline)
				(anchor circle)
			)
			(primitives
				(gr_poly
					(pts
						(arc
							(start -0.2032 -0.2794)
							(mid -0.239121 -0.264521)
							(end -0.254 -0.2286)
						)
						(arc
							(start -0.254 0.2286)
							(mid -0.239121 0.264521)
							(end -0.2032 0.2794)
						)
						(arc
							(start 0.2032 0.2794)
							(mid 0.239121 0.264521)
							(end 0.254 0.2286)
						)
						(arc
							(start 0.254 -0.2286)
							(mid 0.239121 -0.264521)
							(end 0.2032 -0.2794)
						)
					)
					(width 0)
					(fill yes)
				)
			)
		)
		(pad "2" smd custom
			(at 0 0.4318 180)
			(size 0.127 0.127)
			(layers "F.Cu" "F.Mask" "F.Paste")
			(net "FPGA_SMB_HOST_DATA")
			(options
				(clearance outline)
				(anchor circle)
			)
			(primitives
				(gr_poly
					(pts
						(arc
							(start -0.2032 -0.2794)
							(mid -0.239121 -0.264521)
							(end -0.254 -0.2286)
						)
						(arc
							(start -0.254 0.2286)
							(mid -0.239121 0.264521)
							(end -0.2032 0.2794)
						)
						(arc
							(start 0.2032 0.2794)
							(mid 0.239121 0.264521)
							(end 0.254 0.2286)
						)
						(arc
							(start 0.254 -0.2286)
							(mid 0.239121 -0.264521)
							(end 0.2032 -0.2794)
						)
					)
					(width 0)
					(fill yes)
				)
			)
		)
	)
)
